FILE_TYPE = CONNECTIVITY;
{Allegro Design Entry HDL 17.4-2019 S026 (4007227) 1/17/2022}
"PAGE_NUMBER" = 147;
0"NC";
END.
